# T6G (Grand Teton) — schematic netlist excerpt (pin names and nets, part order shuffled) for the footprints in the layout excerpt that follows; sources: Cadence DE-HDL packaged netlist, KiCad conversion of 04192023_DAF0TMB3IC0_F0TG_MB_C_brd_V02_OCP.brd

PR6539  Q_RES  0 5% CHIP  pkg 0402LF  page 364 : A = NC_P0V9_RETIMER_CPU1_IMON3 ; B = GND
R3527  Q_RES  0 5% CHIP  pkg 0402LF  page 250 : A = SMB_PCIE0_3V3AUX_SDA_R5 ; B = SMB_SENSOR_E1S_3V3AUX_SDA
PC6559_1  Q_CAP  22UF 16V 20% X6S  pkg C0805  page 363 : A = SW_P12V_AUX_P0V9_RETIMER_CPU0_FLT ; B = GND

(kicad_pcb
	(version 20260206)
	(generator "pcbnew")
	(generator_version "10.0")
	(general
		(thickness 1.6)
		(legacy_teardrops no)
	)
	(paper "A4")
	(title_block
		(title "04192023_DAF0TMB3IC0_F0TG_MB_C_brd_V02_OCP.brd")
		(comment 1 "Grand Teton / footprints 2300-2302 of 8354")
	)
	(layers
		(0 "F.Cu" signal "TOP")
		(4 "In1.Cu" signal "GND")
		(6 "In2.Cu" signal "IN1")
		(8 "In3.Cu" signal "GND1")
		(10 "In4.Cu" signal "IN2")
		(12 "In5.Cu" signal "GND2")
		(14 "In6.Cu" signal "IN3")
		(16 "In7.Cu" signal "GND3")
		(18 "In8.Cu" signal "VCC")
		(20 "In9.Cu" signal "VCC1")
		(22 "In10.Cu" signal "GND4")
		(24 "In11.Cu" signal "IN4")
		(26 "In12.Cu" signal "GND5")
		(28 "In13.Cu" signal "IN5")
		(30 "In14.Cu" signal "GND6")
		(32 "In15.Cu" signal "IN6")
		(34 "In16.Cu" signal "GND7")
		(2 "B.Cu" signal "BOTTOM")
		(9 "F.Adhes" user "F.Adhesive")
		(11 "B.Adhes" user "B.Adhesive")
		(13 "F.Paste" user "Package Geometry/Pastemask Top")
		(15 "B.Paste" user "Package Geometry/Pastemask Bottom")
		(5 "F.SilkS" user "Ref Des/Silkscreen Top")
		(7 "B.SilkS" user "Ref Des/Silkscreen Bottom")
		(1 "F.Mask" user "Board Geometry/Soldermask Top")
		(3 "B.Mask" user "Board Geometry/Soldermask Bottom")
		(17 "Dwgs.User" user "User.Drawings")
		(19 "Cmts.User" user "User.Comments")
		(21 "Eco1.User" user "User.Eco1")
		(23 "Eco2.User" user "User.Eco2")
		(25 "Edge.Cuts" user "Board Geometry/Outline")
		(27 "Margin" user)
		(31 "F.CrtYd" user "Package Geometry/Place Bound Top")
		(29 "B.CrtYd" user "Package Geometry/Place Bound Bottom")
		(35 "F.Fab" user "Ref Des/Assembly Top")
		(33 "B.Fab" user "Ref Des/Assembly Bottom")
	)
	(footprint ""
		(layer "F.Cu")
		(at 279.513792 -114.64417 180)
		(property "Reference" "R3527"
			(at 0 0 180)
			(layer "F.SilkS")
			(hide yes)
			(effects
				(font
					(size 1.27 1.27)
				)
			)
		)
		(property "Value" ""
			(at 0 0 180)
			(layer "F.Fab")
			(effects
				(font
					(size 1.27 1.27)
				)
			)
		)
		(duplicate_pad_numbers_are_jumpers no)
		(fp_line
			(start 0.7874 0.4064)
			(end -0.7874 0.4064)
			(stroke
				(width 0.1524)
				(type default)
			)
			(layer "F.SilkS")
		)
		(fp_line
			(start 0.7874 -0.4064)
			(end 0.7874 0.4064)
			(stroke
				(width 0.1524)
				(type default)
			)
			(layer "F.SilkS")
		)
		(fp_line
			(start -0.7874 0.4064)
			(end -0.7874 -0.4064)
			(stroke
				(width 0.1524)
				(type default)
			)
			(layer "F.SilkS")
		)
		(fp_line
			(start -0.7874 -0.4064)
			(end 0.7874 -0.4064)
			(stroke
				(width 0.1524)
				(type default)
			)
			(layer "F.SilkS")
		)
		(fp_line
			(start 0.67945 0.3048)
			(end 0.120396 0.3048)
			(stroke
				(width 0.1)
				(type default)
			)
			(layer "F.Fab")
		)
		(fp_line
			(start 0.67945 -0.3048)
			(end 0.67945 0.3048)
			(stroke
				(width 0.1)
				(type default)
			)
			(layer "F.Fab")
		)
		(fp_line
			(start 0.12065 -0.2794)
			(end 0.12065 -0.3048)
			(stroke
				(width 0.1)
				(type default)
			)
			(layer "F.Fab")
		)
		(fp_line
			(start 0.12065 -0.3048)
			(end 0.67945 -0.3048)
			(stroke
				(width 0.1)
				(type default)
			)
			(layer "F.Fab")
		)
		(fp_line
			(start 0.120396 0.3048)
			(end 0.120396 0.2794)
			(stroke
				(width 0.1)
				(type default)
			)
			(layer "F.Fab")
		)
		(fp_line
			(start 0.120396 0.2794)
			(end -0.12065 0.2794)
			(stroke
				(width 0.1)
				(type default)
			)
			(layer "F.Fab")
		)
		(fp_line
			(start -0.12065 0.3048)
			(end -0.67945 0.3048)
			(stroke
				(width 0.1)
				(type default)
			)
			(layer "F.Fab")
		)
		(fp_line
			(start -0.12065 0.2794)
			(end -0.12065 0.3048)
			(stroke
				(width 0.1)
				(type default)
			)
			(layer "F.Fab")
		)
		(fp_line
			(start -0.12065 -0.2794)
			(end 0.12065 -0.2794)
			(stroke
				(width 0.1)
				(type default)
			)
			(layer "F.Fab")
		)
		(fp_line
			(start -0.12065 -0.305054)
			(end -0.12065 -0.2794)
			(stroke
				(width 0.1)
				(type default)
			)
			(layer "F.Fab")
		)
		(fp_line
			(start -0.67945 0.3048)
			(end -0.67945 -0.305054)
			(stroke
				(width 0.1)
				(type default)
			)
			(layer "F.Fab")
		)
		(fp_line
			(start -0.67945 -0.305054)
			(end -0.12065 -0.305054)
			(stroke
				(width 0.1)
				(type default)
			)
			(layer "F.Fab")
		)
		(pad "1" smd circle
			(at -0.40005 0 180)
			(size 0 0)
			(layers "F.Cu" "F.Mask" "F.Paste")
			(net "SMB_PCIE0_3V3AUX_SDA_R5")
		)
		(pad "2" smd circle
			(at 0.40005 0 180)
			(size 0 0)
			(layers "F.Cu" "F.Mask" "F.Paste")
			(net "SMB_SENSOR_E1S_3V3AUX_SDA")
		)
	)
	(footprint ""
		(layer "F.Cu")
		(at 447.237866 -407.6573 180)
		(property "Reference" "PC6559_1"
			(at 0 0 180)
			(layer "F.SilkS")
			(hide yes)
			(effects
				(font
					(size 1.27 1.27)
				)
			)
		)
		(property "Value" ""
			(at 0 0 180)
			(layer "F.Fab")
			(effects
				(font
					(size 1.27 1.27)
				)
			)
		)
		(duplicate_pad_numbers_are_jumpers no)
		(fp_line
			(start 1.524 0.762)
			(end -1.524 0.762)
			(stroke
				(width 0.1524)
				(type default)
			)
			(layer "F.SilkS")
		)
		(fp_line
			(start 1.524 -0.762)
			(end 1.524 0.762)
			(stroke
				(width 0.1524)
				(type default)
			)
			(layer "F.SilkS")
		)
		(fp_line
			(start -1.524 0.762)
			(end -1.524 -0.762)
			(stroke
				(width 0.1524)
				(type default)
			)
			(layer "F.SilkS")
		)
		(fp_line
			(start -1.524 -0.762)
			(end 1.524 -0.762)
			(stroke
				(width 0.1524)
				(type default)
			)
			(layer "F.SilkS")
		)
		(fp_line
			(start 1.1049 0.724916)
			(end 1.1049 -0.724916)
			(stroke
				(width 0.1)
				(type default)
			)
			(layer "F.Fab")
		)
		(fp_line
			(start 1.1049 -0.724916)
			(end -1.1049 -0.724916)
			(stroke
				(width 0.1)
				(type default)
			)
			(layer "F.Fab")
		)
		(fp_line
			(start -1.1049 0.724916)
			(end 1.1049 0.724916)
			(stroke
				(width 0.1)
				(type default)
			)
			(layer "F.Fab")
		)
		(fp_line
			(start -1.1049 -0.724916)
			(end -1.1049 0.724916)
			(stroke
				(width 0.1)
				(type default)
			)
			(layer "F.Fab")
		)
		(pad "1" smd rect
			(at -0.889 0)
			(size 1.016 1.27)
			(layers "F.Cu" "F.Mask" "F.Paste")
			(net "SW_P12V_AUX_P0V9_RETIMER_CPU0_FLT")
		)
		(pad "2" smd rect
			(at 0.889 0)
			(size 1.016 1.27)
			(layers "F.Cu" "F.Mask" "F.Paste")
			(net "GND")
		)
	)
	(footprint ""
		(layer "F.Cu")
		(at 15.527782 -416.050984 90)
		(property "Reference" "PR6539"
			(at 0 0 90)
			(layer "F.SilkS")
			(hide yes)
			(effects
				(font
					(size 1.27 1.27)
				)
			)
		)
		(property "Value" ""
			(at 0 0 90)
			(layer "F.Fab")
			(effects
				(font
					(size 1.27 1.27)
				)
			)
		)
		(duplicate_pad_numbers_are_jumpers no)
		(fp_line
			(start 0.7874 -0.4064)
			(end 0.7874 0.4064)
			(stroke
				(width 0.1524)
				(type default)
			)
			(layer "F.SilkS")
		)
		(fp_line
			(start -0.7874 -0.4064)
			(end 0.7874 -0.4064)
			(stroke
				(width 0.1524)
				(type default)
			)
			(layer "F.SilkS")
		)
		(fp_line
			(start 0.7874 0.4064)
			(end -0.7874 0.4064)
			(stroke
				(width 0.1524)
				(type default)
			)
			(layer "F.SilkS")
		)
		(fp_line
			(start -0.7874 0.4064)
			(end -0.7874 -0.4064)
			(stroke
				(width 0.1524)
				(type default)
			)
			(layer "F.SilkS")
		)
		(fp_line
			(start -0.12065 -0.305054)
			(end -0.12065 -0.2794)
			(stroke
				(width 0.1)
				(type default)
			)
			(layer "F.Fab")
		)
		(fp_line
			(start -0.67945 -0.305054)
			(end -0.12065 -0.305054)
			(stroke
				(width 0.1)
				(type default)
			)
			(layer "F.Fab")
		)
		(fp_line
			(start 0.67945 -0.3048)
			(end 0.67945 0.3048)
			(stroke
				(width 0.1)
				(type default)
			)
			(layer "F.Fab")
		)
		(fp_line
			(start 0.12065 -0.3048)
			(end 0.67945 -0.3048)
			(stroke
				(width 0.1)
				(type default)
			)
			(layer "F.Fab")
		)
		(fp_line
			(start 0.12065 -0.2794)
			(end 0.12065 -0.3048)
			(stroke
				(width 0.1)
				(type default)
			)
			(layer "F.Fab")
		)
		(fp_line
			(start -0.12065 -0.2794)
			(end 0.12065 -0.2794)
			(stroke
				(width 0.1)
				(type default)
			)
			(layer "F.Fab")
		)
		(fp_line
			(start 0.120396 0.2794)
			(end -0.12065 0.2794)
			(stroke
				(width 0.1)
				(type default)
			)
			(layer "F.Fab")
		)
		(fp_line
			(start -0.12065 0.2794)
			(end -0.12065 0.3048)
			(stroke
				(width 0.1)
				(type default)
			)
			(layer "F.Fab")
		)
		(fp_line
			(start 0.67945 0.3048)
			(end 0.120396 0.3048)
			(stroke
				(width 0.1)
				(type default)
			)
			(layer "F.Fab")
		)
		(fp_line
			(start 0.120396 0.3048)
			(end 0.120396 0.2794)
			(stroke
				(width 0.1)
				(type default)
			)
			(layer "F.Fab")
		)
		(fp_line
			(start -0.12065 0.3048)
			(end -0.67945 0.3048)
			(stroke
				(width 0.1)
				(type default)
			)
			(layer "F.Fab")
		)
		(fp_line
			(start -0.67945 0.3048)
			(end -0.67945 -0.305054)
			(stroke
				(width 0.1)
				(type default)
			)
			(layer "F.Fab")
		)
		(pad "1" smd circle
			(at -0.40005 0 90)
			(size 0 0)
			(layers "F.Cu" "F.Mask" "F.Paste")
			(net "NC_P0V9_RETIMER_CPU1_IMON3")
		)
		(pad "2" smd circle
			(at 0.40005 0 90)
			(size 0 0)
			(layers "F.Cu" "F.Mask" "F.Paste")
			(net "GND")
		)
	)
)
